(kicad_pcb
	(version 20260206)
	(generator "pcbnew")
	(generator_version "10.0")
	(general
		(thickness 1.6)
		(legacy_teardrops no)
	)
	(paper "A4")
	(title_block
		(title "01162023_DA0F0TEBIF0_F0T_Expander_BD_F_brd_V02_OCP.brd")
		(comment 1 "Grand Teton / footprints 4691-4697 of 9728")
	)
	(layers
		(0 "F.Cu" signal "TOP")
		(4 "In1.Cu" signal "GND")
		(6 "In2.Cu" signal "VCC")
		(8 "In3.Cu" signal "VCC1")
		(10 "In4.Cu" signal "GND1")
		(12 "In5.Cu" signal "IN1")
		(14 "In6.Cu" signal "GND2")
		(16 "In7.Cu" signal "IN2")
		(18 "In8.Cu" signal "GND3")
		(20 "In9.Cu" signal "IN3")
		(22 "In10.Cu" signal "GND4")
		(24 "In11.Cu" signal "IN4")
		(26 "In12.Cu" signal "GND5")
		(28 "In13.Cu" signal "IN5")
		(30 "In14.Cu" signal "GND6")
		(32 "In15.Cu" signal "IN6")
		(34 "In16.Cu" signal "GND7")
		(2 "B.Cu" signal "BOTTOM")
		(9 "F.Adhes" user "F.Adhesive")
		(11 "B.Adhes" user "B.Adhesive")
		(13 "F.Paste" user "Package Geometry/Pastemask Top")
		(15 "B.Paste" user "Package Geometry/Pastemask Bottom")
		(5 "F.SilkS" user "Ref Des/Silkscreen Top")
		(7 "B.SilkS" user "Ref Des/Silkscreen Bottom")
		(1 "F.Mask" user "Board Geometry/Soldermask Top")
		(3 "B.Mask" user "Board Geometry/Soldermask Bottom")
		(17 "Dwgs.User" user "User.Drawings")
		(19 "Cmts.User" user "User.Comments")
		(21 "Eco1.User" user "User.Eco1")
		(23 "Eco2.User" user "User.Eco2")
		(25 "Edge.Cuts" user "Board Geometry/Outline")
		(27 "Margin" user)
		(31 "F.CrtYd" user "Package Geometry/Place Bound Top")
		(29 "B.CrtYd" user "Package Geometry/Place Bound Bottom")
		(35 "F.Fab" user "Ref Des/Assembly Top")
		(33 "B.Fab" user "Ref Des/Assembly Bottom")
	)
	(footprint ""
		(layer "F.Cu")
		(at 17.792446 -28.225242 180)
		(property "Reference" "C72"
			(at 0 0 180)
			(layer "F.SilkS")
			(hide yes)
			(effects
				(font
					(size 1.27 1.27)
				)
			)
		)
		(property "Value" ""
			(at 0 0 180)
			(layer "F.Fab")
			(effects
				(font
					(size 1.27 1.27)
				)
			)
		)
		(duplicate_pad_numbers_are_jumpers no)
		(fp_line
			(start 0.299974 0.150114)
			(end -0.299974 0.150114)
			(stroke
				(width 0.1)
				(type default)
			)
			(layer "F.Fab")
		)
		(fp_line
			(start 0.299974 -0.150114)
			(end 0.299974 0.150114)
			(stroke
				(width 0.1)
				(type default)
			)
			(layer "F.Fab")
		)
		(fp_line
			(start -0.299974 0.150114)
			(end -0.299974 -0.150114)
			(stroke
				(width 0.1)
				(type default)
			)
			(layer "F.Fab")
		)
		(fp_line
			(start -0.299974 -0.150114)
			(end 0.299974 -0.150114)
			(stroke
				(width 0.1)
				(type default)
			)
			(layer "F.Fab")
		)
		(pad "1" smd rect
			(at -0.2667 0 180)
			(size 0.3048 0.381)
			(layers "F.Cu" "F.Mask" "F.Paste")
			(net "P5E_PEX0_STN2_TX_DN<44>")
		)
		(pad "2" smd rect
			(at 0.2667 0 180)
			(size 0.3048 0.381)
			(layers "F.Cu" "F.Mask" "F.Paste")
			(net "P5E_PEX0_STN2_TX_C_DN<44>")
		)
	)
	(footprint ""
		(layer "F.Cu")
		(at 407.295096 -101.782372 180)
		(property "Reference" "R378"
			(at 0 0 180)
			(layer "F.SilkS")
			(hide yes)
			(effects
				(font
					(size 1.27 1.27)
				)
			)
		)
		(property "Value" ""
			(at 0 0 180)
			(layer "F.Fab")
			(effects
				(font
					(size 1.27 1.27)
				)
			)
		)
		(duplicate_pad_numbers_are_jumpers no)
		(fp_line
			(start 0.7874 0.4064)
			(end -0.7874 0.4064)
			(stroke
				(width 0.1524)
				(type default)
			)
			(layer "F.SilkS")
		)
		(fp_line
			(start 0.7874 -0.4064)
			(end 0.7874 0.4064)
			(stroke
				(width 0.1524)
				(type default)
			)
			(layer "F.SilkS")
		)
		(fp_line
			(start -0.7874 0.4064)
			(end -0.7874 -0.4064)
			(stroke
				(width 0.1524)
				(type default)
			)
			(layer "F.SilkS")
		)
		(fp_line
			(start -0.7874 -0.4064)
			(end 0.7874 -0.4064)
			(stroke
				(width 0.1524)
				(type default)
			)
			(layer "F.SilkS")
		)
		(fp_line
			(start 0.67945 0.3048)
			(end 0.120396 0.3048)
			(stroke
				(width 0.1)
				(type default)
			)
			(layer "F.Fab")
		)
		(fp_line
			(start 0.67945 -0.3048)
			(end 0.67945 0.3048)
			(stroke
				(width 0.1)
				(type default)
			)
			(layer "F.Fab")
		)
		(fp_line
			(start 0.12065 -0.2794)
			(end 0.12065 -0.3048)
			(stroke
				(width 0.1)
				(type default)
			)
			(layer "F.Fab")
		)
		(fp_line
			(start 0.12065 -0.3048)
			(end 0.67945 -0.3048)
			(stroke
				(width 0.1)
				(type default)
			)
			(layer "F.Fab")
		)
		(fp_line
			(start 0.120396 0.3048)
			(end 0.120396 0.2794)
			(stroke
				(width 0.1)
				(type default)
			)
			(layer "F.Fab")
		)
		(fp_line
			(start 0.120396 0.2794)
			(end -0.12065 0.2794)
			(stroke
				(width 0.1)
				(type default)
			)
			(layer "F.Fab")
		)
		(fp_line
			(start -0.12065 0.3048)
			(end -0.67945 0.3048)
			(stroke
				(width 0.1)
				(type default)
			)
			(layer "F.Fab")
		)
		(fp_line
			(start -0.12065 0.2794)
			(end -0.12065 0.3048)
			(stroke
				(width 0.1)
				(type default)
			)
			(layer "F.Fab")
		)
		(fp_line
			(start -0.12065 -0.2794)
			(end 0.12065 -0.2794)
			(stroke
				(width 0.1)
				(type default)
			)
			(layer "F.Fab")
		)
		(fp_line
			(start -0.12065 -0.305054)
			(end -0.12065 -0.2794)
			(stroke
				(width 0.1)
				(type default)
			)
			(layer "F.Fab")
		)
		(fp_line
			(start -0.67945 0.3048)
			(end -0.67945 -0.305054)
			(stroke
				(width 0.1)
				(type default)
			)
			(layer "F.Fab")
		)
		(fp_line
			(start -0.67945 -0.305054)
			(end -0.12065 -0.305054)
			(stroke
				(width 0.1)
				(type default)
			)
			(layer "F.Fab")
		)
		(pad "1" smd circle
			(at -0.40005 0 180)
			(size 0 0)
			(layers "F.Cu" "F.Mask" "F.Paste")
			(net "NCSI_NIC7_TX_EN")
		)
		(pad "2" smd circle
			(at 0.40005 0 180)
			(size 0 0)
			(layers "F.Cu" "F.Mask" "F.Paste")
			(net "GND")
		)
	)
	(footprint ""
		(layer "F.Cu")
		(at 428.837852 -356.244906 90)
		(property "Reference" "C806"
			(at 0 0 90)
			(layer "F.SilkS")
			(hide yes)
			(effects
				(font
					(size 1.27 1.27)
				)
			)
		)
		(property "Value" ""
			(at 0 0 90)
			(layer "F.Fab")
			(effects
				(font
					(size 1.27 1.27)
				)
			)
		)
		(duplicate_pad_numbers_are_jumpers no)
		(fp_line
			(start 0.299974 -0.150114)
			(end 0.299974 0.150114)
			(stroke
				(width 0.1)
				(type default)
			)
			(layer "F.Fab")
		)
		(fp_line
			(start -0.299974 -0.150114)
			(end 0.299974 -0.150114)
			(stroke
				(width 0.1)
				(type default)
			)
			(layer "F.Fab")
		)
		(fp_line
			(start 0.299974 0.150114)
			(end -0.299974 0.150114)
			(stroke
				(width 0.1)
				(type default)
			)
			(layer "F.Fab")
		)
		(fp_line
			(start -0.299974 0.150114)
			(end -0.299974 -0.150114)
			(stroke
				(width 0.1)
				(type default)
			)
			(layer "F.Fab")
		)
		(pad "1" smd rect
			(at -0.2667 0 90)
			(size 0.3048 0.381)
			(layers "F.Cu" "F.Mask" "F.Paste")
			(net "P5E_PEX3_STN7_TX_DP<121>")
		)
		(pad "2" smd rect
			(at 0.2667 0 90)
			(size 0.3048 0.381)
			(layers "F.Cu" "F.Mask" "F.Paste")
			(net "P5E_PEX3_STN7_TX_C_DP<121>")
		)
	)
	(footprint ""
		(layer "F.Cu")
		(at 14.286992 -456.423014 180)
		(property "Reference" "X9"
			(at -0.1778 -1.92913 180)
			(unlocked yes)
			(layer "F.SilkS")
			(effects
				(font
					(size 0.7874 0.5842)
					(thickness 0.1524)
				)
				(justify left)
			)
		)
		(property "Value" ""
			(at 0 0 180)
			(layer "F.Fab")
			(effects
				(font
					(size 1.27 1.27)
				)
			)
		)
		(property "Device Type" "TP_TDR_4P_FTS_MPKT4_H025P0200_IO_TP15_TP_TDR_4P_DIP"
			(at 1.30175 1.27 270)
			(unlocked yes)
			(layer "F.Fab")
			(hide yes)
			(effects
				(font
					(size 0.635 0.4064)
					(thickness 0.1524)
				)
			)
		)
		(property "User Part Number" "TP15"
			(at 1.30175 1.27 270)
			(unlocked yes)
			(layer "Cmts.User")
			(hide yes)
			(effects
				(font
					(size 0.635 0.4064)
					(thickness 0.1524)
				)
			)
		)
		(duplicate_pad_numbers_are_jumpers no)
		(fp_line
			(start 2.54 3.81)
			(end 2.54 3.6703)
			(stroke
				(width 0.1524)
				(type default)
			)
			(layer "F.SilkS")
		)
		(fp_line
			(start 2.54 1.4097)
			(end 2.54 1.1303)
			(stroke
				(width 0.1524)
				(type default)
			)
			(layer "F.SilkS")
		)
		(fp_line
			(start 2.54 -1.1303)
			(end 2.54 -1.27)
			(stroke
				(width 0.1524)
				(type default)
			)
			(layer "F.SilkS")
		)
		(fp_line
			(start 2.54 -1.27)
			(end 0 -1.27)
			(stroke
				(width 0.1524)
				(type default)
			)
			(layer "F.SilkS")
		)
		(fp_line
			(start 0 3.81)
			(end 2.54 3.81)
			(stroke
				(width 0.1524)
				(type default)
			)
			(layer "F.SilkS")
		)
		(fp_line
			(start 0 3.175)
			(end 0 3.81)
			(stroke
				(width 0.1524)
				(type default)
			)
			(layer "F.SilkS")
		)
		(fp_line
			(start 0 0.635)
			(end 0 1.905)
			(stroke
				(width 0.1524)
				(type default)
			)
			(layer "F.SilkS")
		)
		(fp_line
			(start 0 -1.27)
			(end 0 -0.635)
			(stroke
				(width 0.1524)
				(type default)
			)
			(layer "F.SilkS")
		)
		(fp_poly
			(pts
				(xy -0.761746 0) (xy -2.285746 -0.762) (xy -2.285746 0.762)
			)
			(stroke
				(width 0)
				(type default)
			)
			(fill yes)
			(layer "F.SilkS")
		)
		(fp_line
			(start 2.54 3.81)
			(end 2.54 -1.27)
			(stroke
				(width 0.1)
				(type default)
			)
			(layer "F.Fab")
		)
		(fp_line
			(start 2.54 -1.27)
			(end 0 -1.27)
			(stroke
				(width 0.1)
				(type default)
			)
			(layer "F.Fab")
		)
		(fp_line
			(start 0 3.81)
			(end 2.54 3.81)
			(stroke
				(width 0.1)
				(type default)
			)
			(layer "F.Fab")
		)
		(fp_line
			(start 0 -1.27)
			(end 0 3.81)
			(stroke
				(width 0.1)
				(type default)
			)
			(layer "F.Fab")
		)
		(fp_poly
			(pts
				(xy -0.761746 0) (xy -2.285746 -0.762) (xy -2.285746 0.762)
			)
			(stroke
				(width 0)
				(type default)
			)
			(fill yes)
			(layer "F.Fab")
		)
		(pad "1" thru_hole circle
			(at 0 0 180)
			(size 1.0033 1.0033)
			(drill 0.249936)
			(layers "*.Cu" "*.Mask")
			(remove_unused_layers no)
			(net "TDR_DIFF_85_IN1_DIN")
			(clearance 0.10795)
			(thermal_gap 0.10795)
			(padstack
				(mode front_inner_back)
				(layer "Inner"
					(shape circle)
					(size 0.8001 0.8001)
					(clearance 0.1524)
				)
				(layer "B.Cu"
					(shape circle)
					(size 1.0033 1.0033)
					(clearance 0.10795)
				)
			)
		)
		(pad "2" thru_hole circle
			(at 2.54 0 180)
			(size 1.9939 1.9939)
			(drill 0.249936)
			(layers "*.Cu" "*.Mask")
			(remove_unused_layers no)
			(net "COUPON_GND1")
			(clearance 0.10795)
			(thermal_gap 0.10795)
			(padstack
				(mode front_inner_back)
				(layer "Inner"
					(shape circle)
					(size 0.8001 0.8001)
					(clearance 0.1524)
				)
				(layer "B.Cu"
					(shape circle)
					(size 1.9939 1.9939)
					(clearance 0.10795)
				)
			)
		)
		(pad "3" thru_hole circle
			(at 2.54 2.54 180)
			(size 1.9939 1.9939)
			(drill 0.249936)
			(layers "*.Cu" "*.Mask")
			(remove_unused_layers no)
			(net "COUPON_GND1")
			(clearance 0.10795)
			(thermal_gap 0.10795)
			(padstack
				(mode front_inner_back)
				(layer "Inner"
					(shape circle)
					(size 0.8001 0.8001)
					(clearance 0.1524)
				)
				(layer "B.Cu"
					(shape circle)
					(size 1.9939 1.9939)
					(clearance 0.10795)
				)
			)
		)
		(pad "4" thru_hole circle
			(at 0 2.54 180)
			(size 1.0033 1.0033)
			(drill 0.249936)
			(layers "*.Cu" "*.Mask")
			(remove_unused_layers no)
			(net "TDR_DIFF_85_IN1_DIP")
			(clearance 0.10795)
			(thermal_gap 0.10795)
			(padstack
				(mode front_inner_back)
				(layer "Inner"
					(shape circle)
					(size 0.8001 0.8001)
					(clearance 0.1524)
				)
				(layer "B.Cu"
					(shape circle)
					(size 1.0033 1.0033)
					(clearance 0.10795)
				)
			)
		)
	)
	(footprint ""
		(layer "F.Cu")
		(at 374.567958 -54.067456)
		(property "Reference" "PR226"
			(at 0 0 0)
			(layer "F.SilkS")
			(hide yes)
			(effects
				(font
					(size 1.27 1.27)
				)
			)
		)
		(property "Value" ""
			(at 0 0 0)
			(layer "F.Fab")
			(effects
				(font
					(size 1.27 1.27)
				)
			)
		)
		(duplicate_pad_numbers_are_jumpers no)
		(fp_line
			(start -0.7874 -0.4064)
			(end 0.7874 -0.4064)
			(stroke
				(width 0.1524)
				(type default)
			)
			(layer "F.SilkS")
		)
		(fp_line
			(start -0.7874 0.4064)
			(end -0.7874 -0.4064)
			(stroke
				(width 0.1524)
				(type default)
			)
			(layer "F.SilkS")
		)
		(fp_line
			(start 0.7874 -0.4064)
			(end 0.7874 0.4064)
			(stroke
				(width 0.1524)
				(type default)
			)
			(layer "F.SilkS")
		)
		(fp_line
			(start 0.7874 0.4064)
			(end -0.7874 0.4064)
			(stroke
				(width 0.1524)
				(type default)
			)
			(layer "F.SilkS")
		)
		(fp_line
			(start -0.67945 -0.305054)
			(end -0.12065 -0.305054)
			(stroke
				(width 0.1)
				(type default)
			)
			(layer "F.Fab")
		)
		(fp_line
			(start -0.67945 0.3048)
			(end -0.67945 -0.305054)
			(stroke
				(width 0.1)
				(type default)
			)
			(layer "F.Fab")
		)
		(fp_line
			(start -0.12065 -0.305054)
			(end -0.12065 -0.2794)
			(stroke
				(width 0.1)
				(type default)
			)
			(layer "F.Fab")
		)
		(fp_line
			(start -0.12065 -0.2794)
			(end 0.12065 -0.2794)
			(stroke
				(width 0.1)
				(type default)
			)
			(layer "F.Fab")
		)
		(fp_line
			(start -0.12065 0.2794)
			(end -0.12065 0.3048)
			(stroke
				(width 0.1)
				(type default)
			)
			(layer "F.Fab")
		)
		(fp_line
			(start -0.12065 0.3048)
			(end -0.67945 0.3048)
			(stroke
				(width 0.1)
				(type default)
			)
			(layer "F.Fab")
		)
		(fp_line
			(start 0.120396 0.2794)
			(end -0.12065 0.2794)
			(stroke
				(width 0.1)
				(type default)
			)
			(layer "F.Fab")
		)
		(fp_line
			(start 0.120396 0.3048)
			(end 0.120396 0.2794)
			(stroke
				(width 0.1)
				(type default)
			)
			(layer "F.Fab")
		)
		(fp_line
			(start 0.12065 -0.3048)
			(end 0.67945 -0.3048)
			(stroke
				(width 0.1)
				(type default)
			)
			(layer "F.Fab")
		)
		(fp_line
			(start 0.12065 -0.2794)
			(end 0.12065 -0.3048)
			(stroke
				(width 0.1)
				(type default)
			)
			(layer "F.Fab")
		)
		(fp_line
			(start 0.67945 -0.3048)
			(end 0.67945 0.3048)
			(stroke
				(width 0.1)
				(type default)
			)
			(layer "F.Fab")
		)
		(fp_line
			(start 0.67945 0.3048)
			(end 0.120396 0.3048)
			(stroke
				(width 0.1)
				(type default)
			)
			(layer "F.Fab")
		)
		(pad "1" smd circle
			(at -0.40005 0)
			(size 0 0)
			(layers "F.Cu" "F.Mask" "F.Paste")
			(net "P12V_SSD12_OCP")
		)
		(pad "2" smd circle
			(at 0.40005 0)
			(size 0 0)
			(layers "F.Cu" "F.Mask" "F.Paste")
			(net "GND")
		)
	)
	(footprint ""
		(layer "F.Cu")
		(at 283.061156 -169.23385 180)
		(property "Reference" "C917"
			(at 0 0 180)
			(layer "F.SilkS")
			(hide yes)
			(effects
				(font
					(size 1.27 1.27)
				)
			)
		)
		(property "Value" ""
			(at 0 0 180)
			(layer "F.Fab")
			(effects
				(font
					(size 1.27 1.27)
				)
			)
		)
		(duplicate_pad_numbers_are_jumpers no)
		(fp_line
			(start 0.7874 0.4064)
			(end -0.7874 0.4064)
			(stroke
				(width 0.1524)
				(type default)
			)
			(layer "F.SilkS")
		)
		(fp_line
			(start 0.7874 -0.4064)
			(end 0.7874 0.4064)
			(stroke
				(width 0.1524)
				(type default)
			)
			(layer "F.SilkS")
		)
		(fp_line
			(start -0.7874 0.4064)
			(end -0.7874 -0.4064)
			(stroke
				(width 0.1524)
				(type default)
			)
			(layer "F.SilkS")
		)
		(fp_line
			(start -0.7874 -0.4064)
			(end 0.7874 -0.4064)
			(stroke
				(width 0.1524)
				(type default)
			)
			(layer "F.SilkS")
		)
		(fp_line
			(start 0.67945 0.3048)
			(end 0.120396 0.3048)
			(stroke
				(width 0.1)
				(type default)
			)
			(layer "F.Fab")
		)
		(fp_line
			(start 0.67945 -0.3048)
			(end 0.67945 0.3048)
			(stroke
				(width 0.1)
				(type default)
			)
			(layer "F.Fab")
		)
		(fp_line
			(start 0.12065 -0.2794)
			(end 0.12065 -0.3048)
			(stroke
				(width 0.1)
				(type default)
			)
			(layer "F.Fab")
		)
		(fp_line
			(start 0.12065 -0.3048)
			(end 0.67945 -0.3048)
			(stroke
				(width 0.1)
				(type default)
			)
			(layer "F.Fab")
		)
		(fp_line
			(start 0.120396 0.3048)
			(end 0.120396 0.2794)
			(stroke
				(width 0.1)
				(type default)
			)
			(layer "F.Fab")
		)
		(fp_line
			(start 0.120396 0.2794)
			(end -0.12065 0.2794)
			(stroke
				(width 0.1)
				(type default)
			)
			(layer "F.Fab")
		)
		(fp_line
			(start -0.12065 0.3048)
			(end -0.67945 0.3048)
			(stroke
				(width 0.1)
				(type default)
			)
			(layer "F.Fab")
		)
		(fp_line
			(start -0.12065 0.2794)
			(end -0.12065 0.3048)
			(stroke
				(width 0.1)
				(type default)
			)
			(layer "F.Fab")
		)
		(fp_line
			(start -0.12065 -0.2794)
			(end 0.12065 -0.2794)
			(stroke
				(width 0.1)
				(type default)
			)
			(layer "F.Fab")
		)
		(fp_line
			(start -0.12065 -0.305054)
			(end -0.12065 -0.2794)
			(stroke
				(width 0.1)
				(type default)
			)
			(layer "F.Fab")
		)
		(fp_line
			(start -0.67945 0.3048)
			(end -0.67945 -0.305054)
			(stroke
				(width 0.1)
				(type default)
			)
			(layer "F.Fab")
		)
		(fp_line
			(start -0.67945 -0.305054)
			(end -0.12065 -0.305054)
			(stroke
				(width 0.1)
				(type default)
			)
			(layer "F.Fab")
		)
		(pad "1" smd circle
			(at -0.40005 0 180)
			(size 0 0)
			(layers "F.Cu" "F.Mask" "F.Paste")
			(net "P3V3_AUX")
		)
		(pad "2" smd circle
			(at 0.40005 0 180)
			(size 0 0)
			(layers "F.Cu" "F.Mask" "F.Paste")
			(net "GND")
		)
	)
	(footprint ""
		(layer "F.Cu")
		(at 39.280592 -121.005346)
		(property "Reference" "C45"
			(at 0 0 0)
			(layer "F.SilkS")
			(hide yes)
			(effects
				(font
					(size 1.27 1.27)
				)
			)
		)
		(property "Value" ""
			(at 0 0 0)
			(layer "F.Fab")
			(effects
				(font
					(size 1.27 1.27)
				)
			)
		)
		(duplicate_pad_numbers_are_jumpers no)
		(fp_line
			(start -0.299974 -0.150114)
			(end 0.299974 -0.150114)
			(stroke
				(width 0.1)
				(type default)
			)
			(layer "F.Fab")
		)
		(fp_line
			(start -0.299974 0.150114)
			(end -0.299974 -0.150114)
			(stroke
				(width 0.1)
				(type default)
			)
			(layer "F.Fab")
		)
		(fp_line
			(start 0.299974 -0.150114)
			(end 0.299974 0.150114)
			(stroke
				(width 0.1)
				(type default)
			)
			(layer "F.Fab")
		)
		(fp_line
			(start 0.299974 0.150114)
			(end -0.299974 0.150114)
			(stroke
				(width 0.1)
				(type default)
			)
			(layer "F.Fab")
		)
		(pad "1" smd rect
			(at -0.2667 0)
			(size 0.3048 0.381)
			(layers "F.Cu" "F.Mask" "F.Paste")
			(net "P5E_PEX0_STN1_TX_DN<25>")
		)
		(pad "2" smd rect
			(at 0.2667 0)
			(size 0.3048 0.381)
			(layers "F.Cu" "F.Mask" "F.Paste")
			(net "P5E_PEX0_STN1_TX_C_DN<25>")
		)
	)
)
